# S9S_MB_2U (Grand Teton) — schematic netlist excerpt (pin names and nets, part order shuffled) for the footprints in the layout excerpt that follows; sources: Cadence DE-HDL packaged netlist, KiCad conversion of 03242023_DA0F0TMBIJ0_F0T_Motherboard_J_brd_V01_OCP.brd

J4  SCONN288_ADR50017P087CC  SCONN288_ADR50017-P087CC IO  pkg DDR288S_1-1VXB  page 85
  VIN_BULK0  = P12V_S3_AUX_CPU0_NVDIMM
  RFU0  = TP_CHB_CPU0_DIMM2_FRU_0
  VIN_MGMT  = P3V3_AUX
  HSCL  = I3C_SPD_DDRABCD_CPU0_LVC1_SCL_3
  HSDA  = I3C_SPD_DDRABCD_CPU0_LVC1_SDA
  VSS0  = GND
  DQ0_A  = M_B_CPU0_SA_DQ<0>
  VSS1  = GND
  DQ1_A  = M_B_CPU0_SA_DQ<1>
  VSS2  = GND
  DQS0_A_T  = M_B_CPU0_SA_DQS_DP<0>
  DQS0_A_C  = M_B_CPU0_SA_DQS_DN<0>
  VSS3  = GND
  DQ4_A  = M_B_CPU0_SA_DQ<4>
  VSS4  = GND
  DQ5_A  = M_B_CPU0_SA_DQ<5>
  VSS5  = GND
  DQ8_A  = M_B_CPU0_SA_DQ<8>
  VSS6  = GND
  DQ9_A  = M_B_CPU0_SA_DQ<9>
  VSS7  = GND
  DQS1_A_T  = M_B_CPU0_SA_DQS_DP<1>
  DQS1_A_C  = M_B_CPU0_SA_DQS_DN<1>
  VSS8  = GND
  DQ12_A  = M_B_CPU0_SA_DQ<12>
  VSS9  = GND
  DQ13_A  = M_B_CPU0_SA_DQ<13>
  VSS10  = GND
  DQ16_A  = M_B_CPU0_SA_DQ<16>
  VSS11  = GND
  DQ17_A  = M_B_CPU0_SA_DQ<17>
  VSS12  = GND
  DQS2_A_T  = M_B_CPU0_SA_DQS_DP<2>
  DQS2_A_C  = M_B_CPU0_SA_DQS_DN<2>
  VSS13  = GND
  DQ20_A  = M_B_CPU0_SA_DQ<20>
  VSS14  = GND
  DQ21_A  = M_B_CPU0_SA_DQ<21>
  VSS15  = GND
  DQ24_A  = M_B_CPU0_SA_DQ<24>
  VSS16  = GND
  DQ25_A  = M_B_CPU0_SA_DQ<25>
  VSS17  = GND
  DQS3_A_T  = M_B_CPU0_SA_DQS_DP<3>
  DQS3_A_C  = M_B_CPU0_SA_DQS_DN<3>
  VSS18  = GND
  DQ28_A  = M_B_CPU0_SA_DQ<28>
  VSS19  = GND
  DQ29_A  = M_B_CPU0_SA_DQ<29>
  VSS20  = GND
  CB0_A  = M_B_CPU0_SA_CB<0>
  VSS21  = GND
  CB1_A  = M_B_CPU0_SA_CB<1>
  VSS22  = GND
  DQS4_A_T  = M_B_CPU0_SA_DQS_DP<4>
  DQS4_A_C  = M_B_CPU0_SA_DQS_DN<4>
  VSS23  = GND
  CB4_A  = M_B_CPU0_SA_CB<4>
  VSS24  = GND
  CB5_A  = M_B_CPU0_SA_CB<5>
  VSS25  = GND
  ALERT_N  = M_B_CPU0_ALERT_N
  VSS26  = GND
  CS0_A_N  = M_B_CPU0_SA_CS_N<2>
  VSS27  = GND
  CA0_A  = M_B_CPU0_SA_CA<0>
  VSS28  = GND
  CA2_A  = M_B_CPU0_SA_CA<2>
  VSS29  = GND
  CA4_A  = M_B_CPU0_SA_CA<4>
  VSS30  = GND
  CA6_A  = M_B_CPU0_SA_CA<6>
  VSS31  = GND
  PAR_A  = M_B_CPU0_SA_PAR
  VSS32  = GND
  CA0_B  = M_B_CPU0_SB_CA<0>
  VSS33  = GND
  CA2_B  = M_B_CPU0_SB_CA<2>
  VSS34  = GND
  CA4_B  = M_B_CPU0_SB_CA<4>
  VSS35  = GND
  CA6_B  = M_B_CPU0_SB_CA<6>
  VSS36  = GND
  CS0_B_N  = M_B_CPU0_SB_CS_N<2>
  VSS37  = GND
  \lbd||rsp_a_n\  = M_B_CPU0_SA_RSP<1>
  \lbs||rsp_b_n\  = M_B_CPU0_SB_RSP<1>
  VSS38  = GND
  CB4_B  = M_B_CPU0_SB_CB<4>
  VSS39  = GND
  CB5_B  = M_B_CPU0_SB_CB<5>
  VSS40  = GND
  \dqs9_b_t||tdqs9_b_t||dbi4_b_n\  = M_B_CPU0_SB_DQS_DP<9>
  \dqs9_b_c||tdqs9_b_c\  = M_B_CPU0_SB_DQS_DN<9>
  VSS41  = GND
  CB0_B  = M_B_CPU0_SB_CB<0>
  VSS42  = GND
  CB1_B  = M_B_CPU0_SB_CB<1>
  VSS43  = GND
  DQ0_B  = M_B_CPU0_SB_DQ<0>
  VSS44  = GND
  DQ1_B  = M_B_CPU0_SB_DQ<1>
  VSS45  = GND
  DQS0_B_T  = M_B_CPU0_SB_DQS_DP<0>
  DQS0_B_C  = M_B_CPU0_SB_DQS_DN<0>
  VSS46  = GND
  DQ4_B  = M_B_CPU0_SB_DQ<4>
  VSS47  = GND
  DQ5_B  = M_B_CPU0_SB_DQ<5>
  VSS48  = GND
  DQ8_B  = M_B_CPU0_SB_DQ<8>
  VSS49  = GND
  DQ9_B  = M_B_CPU0_SB_DQ<9>
  VSS50  = GND
  DQS1_B_T  = M_B_CPU0_SB_DQS_DP<1>
  DQS1_B_C  = M_B_CPU0_SB_DQS_DN<1>
  VSS51  = GND
  DQ12_B  = M_B_CPU0_SB_DQ<12>
  VSS52  = GND
  DQ13_B  = M_B_CPU0_SB_DQ<13>
  VSS53  = GND
  DQ16_B  = M_B_CPU0_SB_DQ<16>
  VSS54  = GND
  DQ17_B  = M_B_CPU0_SB_DQ<17>
  VSS55  = GND
  DQS2_B_T  = M_B_CPU0_SB_DQS_DP<2>
  DQS2_B_C  = M_B_CPU0_SB_DQS_DN<2>
  VSS56  = GND
  DQ20_B  = M_B_CPU0_SB_DQ<20>
  VSS57  = GND
  DQ21_B  = M_B_CPU0_SB_DQ<21>
  VSS58  = GND
  DQ24_B  = M_B_CPU0_SB_DQ<24>
  VSS59  = GND
  DQ25_B  = M_B_CPU0_SB_DQ<25>
  VSS60  = GND
  DQS3_B_T  = M_B_CPU0_SB_DQS_DP<3>
  DQS3_B_C  = M_B_CPU0_SB_DQS_DN<3>
  VSS61  = GND
  DQ28_B  = M_B_CPU0_SB_DQ<28>
  VSS62  = GND
  DQ29_B  = M_B_CPU0_SB_DQ<29>
  VSS63  = GND
  RFU1  = TP_CHB_CPU0_DIMM2_FRU_1
  VIN_BULK1  = P12V_S3_AUX_CPU0_NVDIMM
  VIN_BULK2  = P12V_S3_AUX_CPU0_NVDIMM
  \pwr_good||fail_n\  = PWRGD_CHB_CPU0_DIMM2
  HSA  = PD_CHB_CPU0_DIMM2_SAA
  RFU2  = TP_CHB_CPU0_DIMM2_FRU_2
  RFU3  = TP_CHB_CPU0_DIMM2_FRU_3
  VSS64  = GND
  DQ2_A  = M_B_CPU0_SA_DQ<2>
  VSS65  = GND
  DQ3_A  = M_B_CPU0_SA_DQ<3>
  VSS66  = GND
  \dqs5_a_c||tdqs5_a_c||dqs5_a_t||tdqs5_a_t\  = M_B_CPU0_SA_DQS_DN<5>
  \dqs5_a_t||tdqs5_a_t\  = M_B_CPU0_SA_DQS_DP<5>
  VSS67  = GND
  DQ6_A  = M_B_CPU0_SA_DQ<6>
  VSS68  = GND
  DQ7_A  = M_B_CPU0_SA_DQ<7>
  VSS69  = GND
  DQ10_A  = M_B_CPU0_SA_DQ<10>
  VSS70  = GND
  DQ11_A  = M_B_CPU0_SA_DQ<11>
  VSS71  = GND
  \dqs6_a_c||tdqs6_a_c||dqs6_a_t||tdqs6_a_t\  = M_B_CPU0_SA_DQS_DN<6>
  \dqs6_a_t||tdqs6_a_t\  = M_B_CPU0_SA_DQS_DP<6>
  VSS72  = GND
  DQ14_A  = M_B_CPU0_SA_DQ<14>
  VSS73  = GND
  DQ15_A  = M_B_CPU0_SA_DQ<15>
  VSS74  = GND
  DQ18_A  = M_B_CPU0_SA_DQ<18>
  VSS75  = GND
  DQ19_A  = M_B_CPU0_SA_DQ<19>
  VSS76  = GND
  \dqs7_a_c||tdqs7_a_c\  = M_B_CPU0_SA_DQS_DN<7>
  \dqs7_a_t||tdqs7_a_t\  = M_B_CPU0_SA_DQS_DP<7>
  VSS77  = GND
  DQ22_A  = M_B_CPU0_SA_DQ<22>
  VSS78  = GND
  DQ23_A  = M_B_CPU0_SA_DQ<23>
  VSS79  = GND
  DQ26_A  = M_B_CPU0_SA_DQ<26>
  VSS80  = GND
  DQ27_A  = M_B_CPU0_SA_DQ<27>
  VSS81  = GND
  \dqs8_a_c||tdqs8_a_c\  = M_B_CPU0_SA_DQS_DN<8>
  \dqs8_a_t||tdqs8_a_t\  = M_B_CPU0_SA_DQS_DP<8>
  VSS82  = GND
  DQ30_A  = M_B_CPU0_SA_DQ<30>
  VSS83  = GND
  DQ31_A  = M_B_CPU0_SA_DQ<31>
  VSS84  = GND
  CB2_A  = M_B_CPU0_SA_CB<2>
  VSS85  = GND
  CB3_A  = M_B_CPU0_SA_CB<3>
  VSS86  = GND
  \dqs9_a_c||tdqs9_a_c\  = M_B_CPU0_SA_DQS_DN<9>
  \dqs9_a_t||tdqs9_a_t\  = M_B_CPU0_SA_DQS_DP<9>
  VSS87  = GND
  CB6_A  = M_B_CPU0_SA_CB<6>
  VSS88  = GND
  CB7_A  = M_B_CPU0_SA_CB<7>
  VSS89  = GND
  RESET_N  = RST_M_AB_CPU0_FPGA_N
  VSS90  = GND
  CS1_A_N  = M_B_CPU0_SA_CS_N<3>
  VSS91  = GND
  CA1_A  = M_B_CPU0_SA_CA<1>
  VSS92  = GND
  CA3_A  = M_B_CPU0_SA_CA<3>
  VSS93  = GND
  CA5_A  = M_B_CPU0_SA_CA<5>
  VSS94  = GND
  CK_T  = M_B_CPU0_CLK_DP<1>
  CK_C  = M_B_CPU0_CLK_DN<1>
  VSS95  = GND
  RFU4  = TP_CHB_CPU0_DIMM2_FRU_4
  CA1_B  = M_B_CPU0_SB_CA<1>
  VSS96  = GND
  CA3_B  = M_B_CPU0_SB_CA<3>
  VSS97  = GND
  CA5_B  = M_B_CPU0_SB_CA<5>
  VSS98  = GND
  PAR_B  = M_B_CPU0_SB_PAR
  VSS99  = GND
  CS1_B_N  = M_B_CPU0_SB_CS_N<3>
  VSS100  = GND
  RFU5  = TP_CHB_CPU0_DIMM2_FRU_5
  RFU6  = TP_CHB_CPU0_DIMM2_FRU_6
  VSS101  = GND
  CB6_B  = M_B_CPU0_SB_CB<6>
  VSS102  = GND
  CB7_B  = M_B_CPU0_SB_CB<7>
  VSS103  = GND
  DQS4_B_C  = M_B_CPU0_SB_DQS_DN<4>
  DQS4_B_T  = M_B_CPU0_SB_DQS_DP<4>
  VSS104  = GND
  CB2_B  = M_B_CPU0_SB_CB<2>
  VSS105  = GND
  CB3_B  = M_B_CPU0_SB_CB<3>
  VSS106  = GND
  DQ2_B  = M_B_CPU0_SB_DQ<2>
  VSS107  = GND
  DQ3_B  = M_B_CPU0_SB_DQ<3>
  VSS108  = GND
  \dqs5_b_c||tdqs5_b_c\  = M_B_CPU0_SB_DQS_DN<5>
  \dqs5_b_t||tdqs5_b_t\  = M_B_CPU0_SB_DQS_DP<5>
  VSS109  = GND
  DQ6_B  = M_B_CPU0_SB_DQ<6>
  VSS110  = GND
  DQ7_B  = M_B_CPU0_SB_DQ<7>
  VSS111  = GND
  DQ10_B  = M_B_CPU0_SB_DQ<10>
  VSS112  = GND
  DQ11_B  = M_B_CPU0_SB_DQ<11>
  VSS113  = GND
  \dqs6_b_c||tdqs6_b_c\  = M_B_CPU0_SB_DQS_DN<6>
  \dqs6_b_t||tdqs6_b_t\  = M_B_CPU0_SB_DQS_DP<6>
  VSS114  = GND
  DQ14_B  = M_B_CPU0_SB_DQ<14>
  VSS115  = GND
  DQ15_B  = M_B_CPU0_SB_DQ<15>
  VSS116  = GND
  DQ18_B  = M_B_CPU0_SB_DQ<18>
  VSS117  = GND
  DQ19_B  = M_B_CPU0_SB_DQ<19>
  VSS118  = GND
  \dqs7_b_c||tdqs7_b_c\  = M_B_CPU0_SB_DQS_DN<7>
  \dqs7_b_t||tdqs7_b_t\  = M_B_CPU0_SB_DQS_DP<7>
  VSS119  = GND
  DQ22_B  = M_B_CPU0_SB_DQ<22>
  VSS120  = GND
  DQ23_B  = M_B_CPU0_SB_DQ<23>
  VSS121  = GND
  DQ26_B  = M_B_CPU0_SB_DQ<26>
  VSS122  = GND
  DQ27_B  = M_B_CPU0_SB_DQ<27>
  VSS123  = GND
  \dqs8_b_c||tdqs8_b_c\  = M_B_CPU0_SB_DQS_DN<8>
  \dqs8_b_t||tdqs8_b_t\  = M_B_CPU0_SB_DQS_DP<8>
  VSS124  = GND
  DQ30_B  = M_B_CPU0_SB_DQ<30>
  VSS125  = GND
  DQ31_B  = M_B_CPU0_SB_DQ<31>
  VSS126  = GND
  G1  = GND
  G2  = GND
  G3  = GND

(kicad_pcb
	(version 20260206)
	(generator "pcbnew")
	(generator_version "10.0")
	(general
		(thickness 1.6)
		(legacy_teardrops no)
	)
	(paper "A4")
	(title_block
		(title "03242023_DA0F0TMBIJ0_F0T_Motherboard_J_brd_V01_OCP.brd")
		(comment 1 "Grand Teton / footprint 1229 of 6105 (J4), pads 275-291 of 291")
	)
	(layers
		(0 "F.Cu" signal "TOP")
		(4 "In1.Cu" signal "GND")
		(6 "In2.Cu" signal "IN1")
		(8 "In3.Cu" signal "GND1")
		(10 "In4.Cu" signal "IN2")
		(12 "In5.Cu" signal "GND2")
		(14 "In6.Cu" signal "IN3")
		(16 "In7.Cu" signal "GND3")
		(18 "In8.Cu" signal "VCC")
		(20 "In9.Cu" signal "VCC1")
		(22 "In10.Cu" signal "GND4")
		(24 "In11.Cu" signal "IN4")
		(26 "In12.Cu" signal "GND5")
		(28 "In13.Cu" signal "IN5")
		(30 "In14.Cu" signal "GND6")
		(32 "In15.Cu" signal "IN6")
		(34 "In16.Cu" signal "GND7")
		(2 "B.Cu" signal "BOTTOM")
		(9 "F.Adhes" user "F.Adhesive")
		(11 "B.Adhes" user "B.Adhesive")
		(13 "F.Paste" user "Package Geometry/Pastemask Top")
		(15 "B.Paste" user "Package Geometry/Pastemask Bottom")
		(5 "F.SilkS" user "Ref Des/Silkscreen Top")
		(7 "B.SilkS" user "Ref Des/Silkscreen Bottom")
		(1 "F.Mask" user "Board Geometry/Soldermask Top")
		(3 "B.Mask" user "Board Geometry/Soldermask Bottom")
		(17 "Dwgs.User" user "User.Drawings")
		(19 "Cmts.User" user "User.Comments")
		(21 "Eco1.User" user "User.Eco1")
		(23 "Eco2.User" user "User.Eco2")
		(25 "Edge.Cuts" user "Board Geometry/Outline")
		(27 "Margin" user)
		(31 "F.CrtYd" user "Package Geometry/Place Bound Top")
		(29 "B.CrtYd" user "Package Geometry/Place Bound Bottom")
		(35 "F.Fab" user "Ref Des/Assembly Top")
		(33 "B.Fab" user "Ref Des/Assembly Bottom")
	)
	(footprint ""
		(layer "F.Cu")
		(at 295.849548 -258.091686)
		(property "Reference" "J4"
			(at -3.683 -81.702148 0)
			(unlocked yes)
			(layer "F.SilkS")
			(effects
				(font
					(size 0.7874 0.5842)
					(thickness 0.1524)
				)
				(justify left)
			)
		)
		(property "Value" ""
			(at 0 0 0)
			(layer "F.Fab")
			(effects
				(font
					(size 1.27 1.27)
				)
			)
		)
		(duplicate_pad_numbers_are_jumpers no)
		(pad "275" smd rect
			(at 2.050034 52.274978 270)
			(size 0.519938 1.4986)
			(layers "F.Cu" "F.Mask" "F.Paste")
			(net "GND")
		)
		(pad "276" smd rect
			(at 2.050034 53.125116 270)
			(size 0.519938 1.4986)
			(layers "F.Cu" "F.Mask" "F.Paste")
			(net "M_B_CPU0_SB_DQ<23>")
		)
		(pad "277" smd rect
			(at 2.050034 53.975 270)
			(size 0.519938 1.4986)
			(layers "F.Cu" "F.Mask" "F.Paste")
			(net "GND")
		)
		(pad "278" smd rect
			(at 2.050034 54.824884 270)
			(size 0.519938 1.4986)
			(layers "F.Cu" "F.Mask" "F.Paste")
			(net "M_B_CPU0_SB_DQ<26>")
		)
		(pad "279" smd rect
			(at 2.050034 55.675022 270)
			(size 0.519938 1.4986)
			(layers "F.Cu" "F.Mask" "F.Paste")
			(net "GND")
		)
		(pad "280" smd rect
			(at 2.050034 56.524906 270)
			(size 0.519938 1.4986)
			(layers "F.Cu" "F.Mask" "F.Paste")
			(net "M_B_CPU0_SB_DQ<27>")
		)
		(pad "281" smd rect
			(at 2.050034 57.375044 270)
			(size 0.519938 1.4986)
			(layers "F.Cu" "F.Mask" "F.Paste")
			(net "GND")
		)
		(pad "282" smd rect
			(at 2.050034 58.224928 270)
			(size 0.519938 1.4986)
			(layers "F.Cu" "F.Mask" "F.Paste")
			(net "M_B_CPU0_SB_DQS_DN<8>")
		)
		(pad "283" smd rect
			(at 2.050034 59.075066 270)
			(size 0.519938 1.4986)
			(layers "F.Cu" "F.Mask" "F.Paste")
			(net "M_B_CPU0_SB_DQS_DP<8>")
		)
		(pad "284" smd rect
			(at 2.050034 59.92495 270)
			(size 0.519938 1.4986)
			(layers "F.Cu" "F.Mask" "F.Paste")
			(net "GND")
		)
		(pad "285" smd rect
			(at 2.050034 60.775088 270)
			(size 0.519938 1.4986)
			(layers "F.Cu" "F.Mask" "F.Paste")
			(net "M_B_CPU0_SB_DQ<30>")
		)
		(pad "286" smd rect
			(at 2.050034 61.624972 270)
			(size 0.519938 1.4986)
			(layers "F.Cu" "F.Mask" "F.Paste")
			(net "GND")
		)
		(pad "287" smd rect
			(at 2.050034 62.47511 270)
			(size 0.519938 1.4986)
			(layers "F.Cu" "F.Mask" "F.Paste")
			(net "M_B_CPU0_SB_DQ<31>")
		)
		(pad "288" smd rect
			(at 2.050034 63.324994 270)
			(size 0.519938 1.4986)
			(layers "F.Cu" "F.Mask" "F.Paste")
			(net "GND")
		)
		(pad "G1" thru_hole oval
			(at 0 -68.97497)
			(size 2.8194 1.5748)
			(drill oval 2.4384 1.1938)
			(layers "*.Cu" "*.Mask")
			(remove_unused_layers no)
			(net "GND")
			(clearance 0.127)
			(thermal_gap 0.127)
		)
		(pad "G2" thru_hole oval
			(at 0 3.875024)
			(size 2.8194 1.5748)
			(drill oval 2.4384 1.1938)
			(layers "*.Cu" "*.Mask")
			(remove_unused_layers no)
			(net "GND")
			(clearance 0.127)
			(thermal_gap 0.127)
		)
		(pad "G3" thru_hole oval
			(at 0 68.97497)
			(size 2.8194 1.5748)
			(drill oval 2.4384 1.1938)
			(layers "*.Cu" "*.Mask")
			(remove_unused_layers no)
			(net "GND")
			(clearance 0.127)
			(thermal_gap 0.127)
		)
	)
)
